# SCM (Grand Teton) — schematic netlist excerpt (pin names and nets, part order shuffled) for the footprints in the layout excerpt that follows; sources: Cadence DE-HDL packaged netlist, KiCad conversion of 12092022_DA0F0TMDCD0_F0T_Management_Board_D_brd_V3_OCP.brd

R796  Q_RES  1K 1% CHIP  pkg 0402LF  page 15 : A = P1V0_AUX ; B = P1V0_SENSOR
R326  Q_RES  120 1% CHIP  pkg 0402LF  page 20 : A = GND ; B = M_BMC_DDR4_MA<0>

(kicad_pcb
	(version 20260206)
	(generator "pcbnew")
	(generator_version "10.0")
	(general
		(thickness 1.6)
		(legacy_teardrops no)
	)
	(paper "A4")
	(title_block
		(title "12092022_DA0F0TMDCD0_F0T_Management_Board_D_brd_V3_OCP.brd")
		(comment 1 "Grand Teton / footprints 1283-1284 of 1440")
	)
	(layers
		(0 "F.Cu" signal "TOP")
		(4 "In1.Cu" signal "GND")
		(6 "In2.Cu" signal "IN1")
		(8 "In3.Cu" signal "GND1")
		(10 "In4.Cu" signal "IN2")
		(12 "In5.Cu" signal "VCC")
		(14 "In6.Cu" signal "VCC1")
		(16 "In7.Cu" signal "IN3")
		(18 "In8.Cu" signal "GND2")
		(20 "In9.Cu" signal "IN4")
		(22 "In10.Cu" signal "GND3")
		(2 "B.Cu" signal "BOTTOM")
		(9 "F.Adhes" user "F.Adhesive")
		(11 "B.Adhes" user "B.Adhesive")
		(13 "F.Paste" user "Package Geometry/Pastemask Top")
		(15 "B.Paste" user "Package Geometry/Pastemask Bottom")
		(5 "F.SilkS" user "Ref Des/Silkscreen Top")
		(7 "B.SilkS" user "Ref Des/Silkscreen Bottom")
		(1 "F.Mask" user "Board Geometry/Soldermask Top")
		(3 "B.Mask" user "Board Geometry/Soldermask Bottom")
		(17 "Dwgs.User" user "User.Drawings")
		(19 "Cmts.User" user "User.Comments")
		(21 "Eco1.User" user "User.Eco1")
		(23 "Eco2.User" user "User.Eco2")
		(25 "Edge.Cuts" user "Board Geometry/Outline")
		(27 "Margin" user)
		(31 "F.CrtYd" user "Package Geometry/Place Bound Top")
		(29 "B.CrtYd" user "Package Geometry/Place Bound Bottom")
		(35 "F.Fab" user "Ref Des/Assembly Top")
		(33 "B.Fab" user "Ref Des/Assembly Bottom")
	)
	(footprint ""
		(layer "B.Cu")
		(at 80.755744 -35.540188 -90)
		(property "Reference" "R326"
			(at 0 0 90)
			(layer "B.SilkS")
			(hide yes)
			(effects
				(font
					(size 1.27 1.27)
				)
				(justify mirror)
			)
		)
		(property "Value" ""
			(at 0 0 90)
			(layer "B.Fab")
			(effects
				(font
					(size 1.27 1.27)
				)
				(justify mirror)
			)
		)
		(duplicate_pad_numbers_are_jumpers no)
		(fp_line
			(start -0.7874 0.4064)
			(end 0.7874 0.4064)
			(stroke
				(width 0.1524)
				(type default)
			)
			(layer "B.SilkS")
		)
		(fp_line
			(start 0.7874 0.4064)
			(end 0.7874 -0.4064)
			(stroke
				(width 0.1524)
				(type default)
			)
			(layer "B.SilkS")
		)
		(fp_line
			(start -0.7874 -0.4064)
			(end -0.7874 0.4064)
			(stroke
				(width 0.1524)
				(type default)
			)
			(layer "B.SilkS")
		)
		(fp_line
			(start 0.7874 -0.4064)
			(end -0.7874 -0.4064)
			(stroke
				(width 0.1524)
				(type default)
			)
			(layer "B.SilkS")
		)
		(fp_line
			(start -0.67945 0.3048)
			(end -0.120396 0.3048)
			(stroke
				(width 0.1)
				(type default)
			)
			(layer "B.Fab")
		)
		(fp_line
			(start -0.120396 0.3048)
			(end -0.120396 0.2794)
			(stroke
				(width 0.1)
				(type default)
			)
			(layer "B.Fab")
		)
		(fp_line
			(start 0.12065 0.3048)
			(end 0.67945 0.3048)
			(stroke
				(width 0.1)
				(type default)
			)
			(layer "B.Fab")
		)
		(fp_line
			(start 0.67945 0.3048)
			(end 0.67945 -0.305054)
			(stroke
				(width 0.1)
				(type default)
			)
			(layer "B.Fab")
		)
		(fp_line
			(start -0.120396 0.2794)
			(end 0.12065 0.2794)
			(stroke
				(width 0.1)
				(type default)
			)
			(layer "B.Fab")
		)
		(fp_line
			(start 0.12065 0.2794)
			(end 0.12065 0.3048)
			(stroke
				(width 0.1)
				(type default)
			)
			(layer "B.Fab")
		)
		(fp_line
			(start -0.12065 -0.2794)
			(end -0.12065 -0.3048)
			(stroke
				(width 0.1)
				(type default)
			)
			(layer "B.Fab")
		)
		(fp_line
			(start 0.12065 -0.2794)
			(end -0.12065 -0.2794)
			(stroke
				(width 0.1)
				(type default)
			)
			(layer "B.Fab")
		)
		(fp_line
			(start -0.67945 -0.3048)
			(end -0.67945 0.3048)
			(stroke
				(width 0.1)
				(type default)
			)
			(layer "B.Fab")
		)
		(fp_line
			(start -0.12065 -0.3048)
			(end -0.67945 -0.3048)
			(stroke
				(width 0.1)
				(type default)
			)
			(layer "B.Fab")
		)
		(fp_line
			(start 0.12065 -0.305054)
			(end 0.12065 -0.2794)
			(stroke
				(width 0.1)
				(type default)
			)
			(layer "B.Fab")
		)
		(fp_line
			(start 0.67945 -0.305054)
			(end 0.12065 -0.305054)
			(stroke
				(width 0.1)
				(type default)
			)
			(layer "B.Fab")
		)
		(pad "1" smd circle
			(at 0.40005 0 90)
			(size 0 0)
			(layers "B.Cu" "B.Mask" "B.Paste")
			(net "GND")
		)
		(pad "2" smd circle
			(at -0.40005 0 90)
			(size 0 0)
			(layers "B.Cu" "B.Mask" "B.Paste")
			(net "M_BMC_DDR4_MA<0>")
		)
	)
	(footprint ""
		(layer "B.Cu")
		(at 50.292 -66.7131 -90)
		(property "Reference" "R796"
			(at 0 0 90)
			(layer "B.SilkS")
			(hide yes)
			(effects
				(font
					(size 1.27 1.27)
				)
				(justify mirror)
			)
		)
		(property "Value" ""
			(at 0 0 90)
			(layer "B.Fab")
			(effects
				(font
					(size 1.27 1.27)
				)
				(justify mirror)
			)
		)
		(duplicate_pad_numbers_are_jumpers no)
		(fp_line
			(start -0.7874 0.4064)
			(end 0.7874 0.4064)
			(stroke
				(width 0.1524)
				(type default)
			)
			(layer "B.SilkS")
		)
		(fp_line
			(start 0.7874 0.4064)
			(end 0.7874 -0.4064)
			(stroke
				(width 0.1524)
				(type default)
			)
			(layer "B.SilkS")
		)
		(fp_line
			(start -0.7874 -0.4064)
			(end -0.7874 0.4064)
			(stroke
				(width 0.1524)
				(type default)
			)
			(layer "B.SilkS")
		)
		(fp_line
			(start 0.7874 -0.4064)
			(end -0.7874 -0.4064)
			(stroke
				(width 0.1524)
				(type default)
			)
			(layer "B.SilkS")
		)
		(fp_line
			(start -0.67945 0.3048)
			(end -0.120396 0.3048)
			(stroke
				(width 0.1)
				(type default)
			)
			(layer "B.Fab")
		)
		(fp_line
			(start -0.120396 0.3048)
			(end -0.120396 0.2794)
			(stroke
				(width 0.1)
				(type default)
			)
			(layer "B.Fab")
		)
		(fp_line
			(start 0.12065 0.3048)
			(end 0.67945 0.3048)
			(stroke
				(width 0.1)
				(type default)
			)
			(layer "B.Fab")
		)
		(fp_line
			(start 0.67945 0.3048)
			(end 0.67945 -0.305054)
			(stroke
				(width 0.1)
				(type default)
			)
			(layer "B.Fab")
		)
		(fp_line
			(start -0.120396 0.2794)
			(end 0.12065 0.2794)
			(stroke
				(width 0.1)
				(type default)
			)
			(layer "B.Fab")
		)
		(fp_line
			(start 0.12065 0.2794)
			(end 0.12065 0.3048)
			(stroke
				(width 0.1)
				(type default)
			)
			(layer "B.Fab")
		)
		(fp_line
			(start -0.12065 -0.2794)
			(end -0.12065 -0.3048)
			(stroke
				(width 0.1)
				(type default)
			)
			(layer "B.Fab")
		)
		(fp_line
			(start 0.12065 -0.2794)
			(end -0.12065 -0.2794)
			(stroke
				(width 0.1)
				(type default)
			)
			(layer "B.Fab")
		)
		(fp_line
			(start -0.67945 -0.3048)
			(end -0.67945 0.3048)
			(stroke
				(width 0.1)
				(type default)
			)
			(layer "B.Fab")
		)
		(fp_line
			(start -0.12065 -0.3048)
			(end -0.67945 -0.3048)
			(stroke
				(width 0.1)
				(type default)
			)
			(layer "B.Fab")
		)
		(fp_line
			(start 0.12065 -0.305054)
			(end 0.12065 -0.2794)
			(stroke
				(width 0.1)
				(type default)
			)
			(layer "B.Fab")
		)
		(fp_line
			(start 0.67945 -0.305054)
			(end 0.12065 -0.305054)
			(stroke
				(width 0.1)
				(type default)
			)
			(layer "B.Fab")
		)
		(pad "1" smd circle
			(at 0.40005 0 90)
			(size 0 0)
			(layers "B.Cu" "B.Mask" "B.Paste")
			(net "P1V0_AUX")
		)
		(pad "2" smd circle
			(at -0.40005 0 90)
			(size 0 0)
			(layers "B.Cu" "B.Mask" "B.Paste")
			(net "P1V0_SENSOR")
		)
	)
)
